(kicad_pcb
	(version 20240108)
	(generator "pcbnew")
	(generator_version "8.0")
	(general
		(thickness 1.62)
		(legacy_teardrops no)
	)
	(paper "A4")
	(title_block
		(title "Jetson Orin Baseboard")
		(date "2025-03-12")
		(rev "1.3.4")
		(company "Antmicro Ltd")
		(comment 1 "www.antmicro.com")
		(comment 9 "footprints 212-216 of 677")
	)
	(layers
		(0 "F.Cu" signal)
		(1 "In1.Cu" signal)
		(2 "In2.Cu" signal)
		(3 "In3.Cu" signal)
		(4 "In4.Cu" jumper)
		(5 "In5.Cu" signal)
		(6 "In6.Cu" signal)
		(31 "B.Cu" signal)
		(32 "B.Adhes" user "B.Adhesive")
		(33 "F.Adhes" user "F.Adhesive")
		(34 "B.Paste" user)
		(35 "F.Paste" user)
		(36 "B.SilkS" user "B.Silkscreen")
		(37 "F.SilkS" user "F.Silkscreen")
		(38 "B.Mask" user)
		(39 "F.Mask" user)
		(40 "Dwgs.User" user "User.Drawings")
		(41 "Cmts.User" user "User.Comments")
		(42 "Eco1.User" user "User.Eco1")
		(43 "Eco2.User" user "User.Eco2")
		(44 "Edge.Cuts" user)
		(45 "Margin" user)
		(46 "B.CrtYd" user "B.Courtyard")
		(47 "F.CrtYd" user "F.Courtyard")
		(48 "B.Fab" user)
		(49 "F.Fab" user)
	)
	(footprint "antmicro-footprints:R_0402_1005Metric"
		(layer "F.Cu")
		(at 80.23 87.22 90)
		(descr "Resistor SMD 0402")
		(tags "resistor SMD 0402")
		(property "Reference" "R238"
			(at 0.72 0.44 90)
			(layer "F.SilkS")
			(effects
				(font
					(size 0.7 0.7)
					(thickness 0.15)
				)
				(justify left bottom)
			)
		)
		(property "Value" "R_10k_0402"
			(at -1.011843 1.772047 90)
			(layer "F.Fab")
			(effects
				(font
					(size 0.7 0.7)
					(thickness 0.15)
				)
				(justify left bottom)
			)
		)
		(property "Footprint" "antmicro-footprints:R_0402_1005Metric"
			(at 0 0 90)
			(layer "F.Fab")
			(hide yes)
			(effects
				(font
					(size 1.27 1.27)
					(thickness 0.15)
				)
			)
		)
		(property "Datasheet" "https://www.bourns.com/docs/product-datasheets/cr.pdf"
			(at 0 0 90)
			(layer "F.Fab")
			(hide yes)
			(effects
				(font
					(size 1.27 1.27)
					(thickness 0.15)
				)
			)
		)
		(property "Author" "Antmicro"
			(at 167.45 6.99 0)
			(layer "F.Fab")
			(hide yes)
			(effects
				(font
					(size 1 1)
					(thickness 0.15)
				)
			)
		)
		(property "License" "Apache-2.0"
			(at 167.45 6.99 0)
			(layer "F.Fab")
			(hide yes)
			(effects
				(font
					(size 1 1)
					(thickness 0.15)
				)
			)
		)
		(property "MPN" "CR0402-FX-1002GLF"
			(at 167.45 6.99 0)
			(layer "F.Fab")
			(hide yes)
			(effects
				(font
					(size 1 1)
					(thickness 0.15)
				)
			)
		)
		(property "Manufacturer" "Bourns"
			(at 167.45 6.99 0)
			(layer "F.Fab")
			(hide yes)
			(effects
				(font
					(size 1 1)
					(thickness 0.15)
				)
			)
		)
		(property "Tolerance" "1%"
			(at 167.45 6.99 0)
			(layer "F.Fab")
			(hide yes)
			(effects
				(font
					(size 1 1)
					(thickness 0.15)
				)
			)
		)
		(property "Val" "10k"
			(at 167.45 6.99 0)
			(layer "F.Fab")
			(hide yes)
			(effects
				(font
					(size 1 1)
					(thickness 0.15)
				)
			)
		)
		(sheetname "Supply")
		(sheetfile "supply.kicad_sch")
		(attr smd)
		(fp_rect
			(start -0.925 -0.47)
			(end 0.925 0.47)
			(stroke
				(width 0.05)
				(type default)
			)
			(fill none)
			(layer "F.CrtYd")
		)
		(fp_rect
			(start -0.5 -0.25)
			(end 0.5 0.25)
			(stroke
				(width 0.15)
				(type solid)
			)
			(fill none)
			(layer "F.Fab")
		)
		(fp_text user "${REFERENCE}"
			(at -0.95 3.168 90)
			(layer "F.Fab")
			(hide yes)
			(effects
				(font
					(size 0.7 0.7)
					(thickness 0.15)
				)
				(justify left bottom)
			)
		)
		(fp_text user "Author: Antmicro"
			(at -0.95 4.169 90)
			(layer "F.Fab")
			(hide yes)
			(effects
				(font
					(size 0.7 0.7)
					(thickness 0.15)
				)
				(justify left bottom)
			)
		)
		(fp_text user "License: Apache-2.0"
			(at -0.95 5.169 90)
			(layer "F.Fab")
			(hide yes)
			(effects
				(font
					(size 0.7 0.7)
					(thickness 0.15)
				)
				(justify left bottom)
			)
		)
		(pad "1" smd roundrect
			(at -0.48 0 90)
			(size 0.59 0.64)
			(layers "F.Cu" "F.Paste" "F.Mask")
			(roundrect_rratio 0.25)
			(net 1 "GND")
			(pintype "passive")
		)
		(pad "2" smd roundrect
			(at 0.48 0 90)
			(size 0.59 0.64)
			(layers "F.Cu" "F.Paste" "F.Mask")
			(roundrect_rratio 0.25)
			(net 711 "/Supply/3V3_FB")
			(pintype "passive")
		)
	)
	(footprint "antmicro-footprints:C_0603_1608Metric"
		(layer "F.Cu")
		(at 114.7 102.85 90)
		(descr "Capacitor SMD 0603")
		(tags "capacitor 0603")
		(property "Reference" "C12"
			(at -1.55 -0.6 90)
			(layer "F.SilkS")
			(effects
				(font
					(size 0.7 0.7)
					(thickness 0.15)
				)
				(justify left bottom)
			)
		)
		(property "Value" "C_10u_0603"
			(at 0 1.6 90)
			(layer "F.Fab")
			(effects
				(font
					(size 0.7 0.7)
					(thickness 0.15)
				)
				(justify left bottom)
			)
		)
		(property "Footprint" "antmicro-footprints:C_0603_1608Metric"
			(at 0 0 90)
			(layer "F.Fab")
			(hide yes)
			(effects
				(font
					(size 1.27 1.27)
					(thickness 0.15)
				)
			)
		)
		(property "Datasheet" "https://www.murata.com/products/productdetail?partno=GRM188R61A106KE69%23"
			(at 0 0 90)
			(layer "F.Fab")
			(hide yes)
			(effects
				(font
					(size 1.27 1.27)
					(thickness 0.15)
				)
			)
		)
		(property "Author" "Antmicro"
			(at 217.55 -11.85 0)
			(layer "F.Fab")
			(hide yes)
			(effects
				(font
					(size 1 1)
					(thickness 0.15)
				)
			)
		)
		(property "Dielectric" "template_dielectric"
			(at 217.55 -11.85 0)
			(layer "F.Fab")
			(hide yes)
			(effects
				(font
					(size 1 1)
					(thickness 0.15)
				)
			)
		)
		(property "License" "Apache-2.0"
			(at 217.55 -11.85 0)
			(layer "F.Fab")
			(hide yes)
			(effects
				(font
					(size 1 1)
					(thickness 0.15)
				)
			)
		)
		(property "MPN" "GRM188R61A106KE69D"
			(at 217.55 -11.85 0)
			(layer "F.Fab")
			(hide yes)
			(effects
				(font
					(size 1 1)
					(thickness 0.15)
				)
			)
		)
		(property "Manufacturer" "Murata"
			(at 217.55 -11.85 0)
			(layer "F.Fab")
			(hide yes)
			(effects
				(font
					(size 1 1)
					(thickness 0.15)
				)
			)
		)
		(property "Val" "10u"
			(at 217.55 -11.85 0)
			(layer "F.Fab")
			(hide yes)
			(effects
				(font
					(size 1 1)
					(thickness 0.15)
				)
			)
		)
		(property "Voltage" ""
			(at 217.55 -11.85 0)
			(layer "F.Fab")
			(hide yes)
			(effects
				(font
					(size 1 1)
					(thickness 0.15)
				)
			)
		)
		(sheetname "M.2")
		(sheetfile "m-2.kicad_sch")
		(attr smd)
		(fp_line
			(start -0.15 -0.4)
			(end 0.15 -0.4)
			(stroke
				(width 0.15)
				(type solid)
			)
			(layer "F.SilkS")
		)
		(fp_line
			(start -0.15 0.4)
			(end 0.15 0.4)
			(stroke
				(width 0.15)
				(type solid)
			)
			(layer "F.SilkS")
		)
		(fp_rect
			(start -1.25 -0.65)
			(end 1.25 0.65)
			(stroke
				(width 0.05)
				(type solid)
			)
			(fill none)
			(layer "F.CrtYd")
		)
		(fp_rect
			(start -0.8 -0.4)
			(end 0.8 0.4)
			(stroke
				(width 0.15)
				(type solid)
			)
			(fill none)
			(layer "F.Fab")
		)
		(fp_text user "License: Apache-2.0"
			(at -1.682 5.895 90)
			(layer "F.Fab")
			(hide yes)
			(effects
				(font
					(size 0.7 0.7)
					(thickness 0.15)
				)
				(justify left bottom)
			)
		)
		(fp_text user "${REFERENCE}"
			(at -1.682 3.895 90)
			(layer "F.Fab")
			(hide yes)
			(effects
				(font
					(size 0.7 0.7)
					(thickness 0.15)
				)
				(justify left bottom)
			)
		)
		(fp_text user "Author: Antmicro"
			(at -1.682 4.894 90)
			(layer "F.Fab")
			(hide yes)
			(effects
				(font
					(size 0.7 0.7)
					(thickness 0.15)
				)
				(justify left bottom)
			)
		)
		(pad "1" smd roundrect
			(at -0.7 0 90)
			(size 0.8 1)
			(layers "F.Cu" "F.Paste" "F.Mask")
			(roundrect_rratio 0.2)
			(net 87 "+3V3")
			(pintype "passive")
		)
		(pad "2" smd roundrect
			(at 0.7 0 90)
			(size 0.8 1)
			(layers "F.Cu" "F.Paste" "F.Mask")
			(roundrect_rratio 0.2)
			(net 1 "GND")
			(pintype "passive")
		)
	)
	(footprint "antmicro-footprints:R_0402_1005Metric"
		(layer "F.Cu")
		(at 85.4 114.8)
		(descr "Resistor SMD 0402")
		(tags "resistor SMD 0402")
		(property "Reference" "R226"
			(at -3.98 3.72 0)
			(layer "F.SilkS")
			(effects
				(font
					(size 0.7 0.7)
					(thickness 0.15)
				)
				(justify left bottom)
			)
		)
		(property "Value" "R_0R_0402"
			(at 0 1.4 0)
			(layer "F.Fab")
			(effects
				(font
					(size 0.7 0.7)
					(thickness 0.15)
				)
				(justify left bottom)
			)
		)
		(property "Footprint" "antmicro-footprints:R_0402_1005Metric"
			(at 0 0 0)
			(layer "F.Fab")
			(hide yes)
			(effects
				(font
					(size 1.27 1.27)
					(thickness 0.15)
				)
			)
		)
		(property "Datasheet" "https://industrial.panasonic.com/cdbs/www-data/pdf/RDA0000/AOA0000C301.pdf"
			(at 0 0 0)
			(layer "F.Fab")
			(hide yes)
			(effects
				(font
					(size 1.27 1.27)
					(thickness 0.15)
				)
			)
		)
		(property "Author" "Antmicro"
			(at 0 0 0)
			(layer "F.Fab")
			(hide yes)
			(effects
				(font
					(size 1 1)
					(thickness 0.15)
				)
			)
		)
		(property "Current" "1A"
			(at 0 0 0)
			(layer "F.Fab")
			(hide yes)
			(effects
				(font
					(size 1 1)
					(thickness 0.15)
				)
			)
		)
		(property "License" "Apache-2.0"
			(at 0 0 0)
			(layer "F.Fab")
			(hide yes)
			(effects
				(font
					(size 1 1)
					(thickness 0.15)
				)
			)
		)
		(property "MPN" "ERJ2GE0R00X"
			(at 0 0 0)
			(layer "F.Fab")
			(hide yes)
			(effects
				(font
					(size 1 1)
					(thickness 0.15)
				)
			)
		)
		(property "Manufacturer" "Panasonic"
			(at 0 0 0)
			(layer "F.Fab")
			(hide yes)
			(effects
				(font
					(size 1 1)
					(thickness 0.15)
				)
			)
		)
		(property "Tolerance" ""
			(at 0 0 0)
			(layer "F.Fab")
			(hide yes)
			(effects
				(font
					(size 1 1)
					(thickness 0.15)
				)
			)
		)
		(property "Val" "0R"
			(at 0 0 0)
			(layer "F.Fab")
			(hide yes)
			(effects
				(font
					(size 1 1)
					(thickness 0.15)
				)
			)
		)
		(sheetname "HDMI")
		(sheetfile "hdmi.kicad_sch")
		(attr smd)
		(fp_rect
			(start -0.925 -0.47)
			(end 0.925 0.47)
			(stroke
				(width 0.05)
				(type default)
			)
			(fill none)
			(layer "F.CrtYd")
		)
		(fp_rect
			(start -0.5 -0.25)
			(end 0.5 0.25)
			(stroke
				(width 0.15)
				(type solid)
			)
			(fill none)
			(layer "F.Fab")
		)
		(fp_text user "Author: Antmicro"
			(at -0.95 4.169 0)
			(layer "F.Fab")
			(hide yes)
			(effects
				(font
					(size 0.7 0.7)
					(thickness 0.15)
				)
				(justify left bottom)
			)
		)
		(fp_text user "License: Apache-2.0"
			(at -0.95 5.169 0)
			(layer "F.Fab")
			(hide yes)
			(effects
				(font
					(size 0.7 0.7)
					(thickness 0.15)
				)
				(justify left bottom)
			)
		)
		(fp_text user "${REFERENCE}"
			(at -0.95 3.168 0)
			(layer "F.Fab")
			(hide yes)
			(effects
				(font
					(size 0.7 0.7)
					(thickness 0.15)
				)
				(justify left bottom)
			)
		)
		(pad "1" smd roundrect
			(at -0.48 0)
			(size 0.59 0.64)
			(layers "F.Cu" "F.Paste" "F.Mask")
			(roundrect_rratio 0.25)
			(net 703 "/HDMI/HDMI_HPD")
			(pintype "passive")
		)
		(pad "2" smd roundrect
			(at 0.48 0)
			(size 0.59 0.64)
			(layers "F.Cu" "F.Paste" "F.Mask")
			(roundrect_rratio 0.25)
			(net 529 "/HDMI/HDMI_HPD_5V")
			(pintype "passive")
		)
	)
	(footprint "antmicro-footprints:SOD-923"
		(layer "F.Cu")
		(at 60.925 91.4)
		(property "Reference" "D32"
			(at 0.605 0.46 0)
			(unlocked yes)
			(layer "F.SilkS")
			(effects
				(font
					(size 0.7 0.7)
					(thickness 0.15)
				)
				(justify left bottom)
			)
		)
		(property "Value" "ESD9X5.0ST5G"
			(at 0 1.3 0)
			(unlocked yes)
			(layer "F.Fab")
			(effects
				(font
					(size 0.7 0.7)
					(thickness 0.15)
				)
				(justify left bottom)
			)
		)
		(property "Footprint" "antmicro-footprints:SOD-923"
			(at 0 0 0)
			(layer "B.Fab")
			(hide yes)
			(effects
				(font
					(size 1.27 1.27)
					(thickness 0.15)
				)
				(justify mirror)
			)
		)
		(property "Datasheet" "https://www.onsemi.com/pdf/datasheet/esd9x3.3st5g-d.pdf"
			(at 0 0 0)
			(layer "B.Fab")
			(hide yes)
			(effects
				(font
					(size 1.27 1.27)
					(thickness 0.15)
				)
				(justify mirror)
			)
		)
		(property "Author" "Antmicro"
			(at 143.39 -28.57 90)
			(layer "F.Fab")
			(hide yes)
			(effects
				(font
					(size 1 1)
					(thickness 0.15)
				)
			)
		)
		(property "License" "Apache-2.0"
			(at 143.39 -28.57 90)
			(layer "F.Fab")
			(hide yes)
			(effects
				(font
					(size 1 1)
					(thickness 0.15)
				)
			)
		)
		(property "MPN" "ESD9X5.0ST5G"
			(at 143.39 -28.57 90)
			(layer "F.Fab")
			(hide yes)
			(effects
				(font
					(size 1 1)
					(thickness 0.15)
				)
			)
		)
		(property "Manufacturer" "ON Semiconductor"
			(at 143.39 -28.57 90)
			(layer "F.Fab")
			(hide yes)
			(effects
				(font
					(size 1 1)
					(thickness 0.15)
				)
			)
		)
		(sheetname "Supply")
		(sheetfile "supply.kicad_sch")
		(attr smd)
		(fp_line
			(start -0.5 -0.4)
			(end 0.5 -0.4)
			(stroke
				(width 0.15)
				(type solid)
			)
			(layer "F.SilkS")
		)
		(fp_line
			(start -0.5 -0.3)
			(end -0.5 -0.4)
			(stroke
				(width 0.15)
				(type solid)
			)
			(layer "F.SilkS")
		)
		(fp_line
			(start -0.5 0.4)
			(end -0.5 0.3)
			(stroke
				(width 0.15)
				(type solid)
			)
			(layer "F.SilkS")
		)
		(fp_line
			(start -0.5 0.4)
			(end 0.5 0.4)
			(stroke
				(width 0.15)
				(type solid)
			)
			(layer "F.SilkS")
		)
		(fp_line
			(start -0.16 -0.4)
			(end -0.16 0.4)
			(stroke
				(width 0.15)
				(type solid)
			)
			(layer "F.SilkS")
		)
		(fp_line
			(start 0.5 -0.4)
			(end 0.5 -0.3)
			(stroke
				(width 0.15)
				(type solid)
			)
			(layer "F.SilkS")
		)
		(fp_line
			(start 0.5 0.4)
			(end 0.5 0.3)
			(stroke
				(width 0.15)
				(type solid)
			)
			(layer "F.SilkS")
		)
		(fp_rect
			(start -0.68 -0.41)
			(end 0.68 0.41)
			(stroke
				(width 0.05)
				(type solid)
			)
			(fill none)
			(layer "F.CrtYd")
		)
		(fp_line
			(start -0.202 -0.3)
			(end -0.202 0.298)
			(stroke
				(width 0.15)
				(type solid)
			)
			(layer "F.Fab")
		)
		(fp_rect
			(start -0.402 -0.3)
			(end 0.4 0.298)
			(stroke
				(width 0.15)
				(type solid)
			)
			(fill none)
			(layer "F.Fab")
		)
		(fp_text user "${REFERENCE}"
			(at -0.68 3.3 0)
			(unlocked yes)
			(layer "F.Fab")
			(hide yes)
			(effects
				(font
					(size 0.7 0.7)
					(thickness 0.15)
				)
				(justify left bottom)
			)
		)
		(fp_text user "License: Apache-2.0"
			(at -0.68 4.5 0)
			(layer "F.Fab")
			(hide yes)
			(effects
				(font
					(size 0.7 0.7)
					(thickness 0.15)
				)
				(justify left top)
			)
		)
		(fp_text user "Author: Antmicro"
			(at -0.68 5.7 0)
			(layer "F.Fab")
			(hide yes)
			(effects
				(font
					(size 0.7 0.7)
					(thickness 0.15)
				)
				(justify left top)
			)
		)
		(pad "1" smd roundrect
			(at -0.438 0)
			(size 0.4 0.325)
			(layers "F.Cu" "F.Paste" "F.Mask")
			(roundrect_rratio 0.25)
			(net 787 "+5V_SoM")
			(pinfunction "C")
			(pintype "passive")
		)
		(pad "2" smd roundrect
			(at 0.436 0)
			(size 0.4 0.325)
			(layers "F.Cu" "F.Paste" "F.Mask")
			(roundrect_rratio 0.25)
			(net 1 "GND")
			(pinfunction "A")
			(pintype "passive")
		)
	)
	(footprint "antmicro-footprints:C_0402_1005Metric"
		(layer "F.Cu")
		(at 61.39 100.52 180)
		(descr "Capacitor SMD 0402")
		(tags "capacitor SMD 0402")
		(property "Reference" "C156"
			(at -5.535 -3.555 0)
			(layer "F.SilkS")
			(effects
				(font
					(size 0.7 0.7)
					(thickness 0.15)
				)
				(justify right bottom)
			)
		)
		(property "Value" "C_4u7_25V_0402"
			(at -1.022927 2.155213 0)
			(layer "F.Fab")
			(effects
				(font
					(size 0.7 0.7)
					(thickness 0.15)
				)
				(justify right bottom)
			)
		)
		(property "Footprint" "antmicro-footprints:C_0402_1005Metric"
			(at 0 0 180)
			(layer "F.Fab")
			(hide yes)
			(effects
				(font
					(size 1.27 1.27)
					(thickness 0.15)
				)
			)
		)
		(property "Datasheet" "https://www.murata.com/products/productdetail?partno=GRM155C61E475ME15%23"
			(at 0 0 180)
			(layer "F.Fab")
			(hide yes)
			(effects
				(font
					(size 1.27 1.27)
					(thickness 0.15)
				)
			)
		)
		(property "Author" "Antmicro"
			(at 122.78 201.04 0)
			(layer "F.Fab")
			(hide yes)
			(effects
				(font
					(size 1 1)
					(thickness 0.15)
				)
			)
		)
		(property "Dielectric" "X5S"
			(at 122.78 201.04 0)
			(layer "F.Fab")
			(hide yes)
			(effects
				(font
					(size 1 1)
					(thickness 0.15)
				)
			)
		)
		(property "License" "Apache-2.0"
			(at 122.78 201.04 0)
			(layer "F.Fab")
			(hide yes)
			(effects
				(font
					(size 1 1)
					(thickness 0.15)
				)
			)
		)
		(property "MPN" "GRM155C61E475ME15J"
			(at 122.78 201.04 0)
			(layer "F.Fab")
			(hide yes)
			(effects
				(font
					(size 1 1)
					(thickness 0.15)
				)
			)
		)
		(property "Manufacturer" "Murata"
			(at 122.78 201.04 0)
			(layer "F.Fab")
			(hide yes)
			(effects
				(font
					(size 1 1)
					(thickness 0.15)
				)
			)
		)
		(property "Val" "4u7"
			(at 122.78 201.04 0)
			(layer "F.Fab")
			(hide yes)
			(effects
				(font
					(size 1 1)
					(thickness 0.15)
				)
			)
		)
		(property "Voltage" "25V"
			(at 122.78 201.04 0)
			(layer "F.Fab")
			(hide yes)
			(effects
				(font
					(size 1 1)
					(thickness 0.15)
				)
			)
		)
		(sheetname "Supply")
		(sheetfile "supply.kicad_sch")
		(attr smd)
		(fp_rect
			(start -0.925 -0.47)
			(end 0.925 0.47)
			(stroke
				(width 0.05)
				(type default)
			)
			(fill none)
			(layer "F.CrtYd")
		)
		(fp_line
			(start 0.504 0.248)
			(end -0.494 0.248)
			(stroke
				(width 0.15)
				(type solid)
			)
			(layer "F.Fab")
		)
		(fp_line
			(start 0.504 -0.25)
			(end 0.504 0.248)
			(stroke
				(width 0.15)
				(type solid)
			)
			(layer "F.Fab")
		)
		(fp_line
			(start -0.494 0.248)
			(end -0.494 -0.25)
			(stroke
				(width 0.15)
				(type solid)
			)
			(layer "F.Fab")
		)
		(fp_line
			(start -0.494 -0.25)
			(end 0.504 -0.25)
			(stroke
				(width 0.15)
				(type solid)
			)
			(layer "F.Fab")
		)
		(fp_text user "Author: Antmicro"
			(at -0.939 3.399 0)
			(layer "F.Fab")
			(hide yes)
			(effects
				(font
					(size 0.7 0.7)
					(thickness 0.15)
				)
				(justify right bottom)
			)
		)
		(fp_text user "License: Apache-2.0"
			(at -0.939 5.799 0)
			(layer "F.Fab")
			(hide yes)
			(effects
				(font
					(size 0.7 0.7)
					(thickness 0.15)
				)
				(justify right bottom)
			)
		)
		(fp_text user "${REFERENCE}"
			(at -0.939 4.599 0)
			(layer "F.Fab")
			(hide yes)
			(effects
				(font
					(size 0.7 0.7)
					(thickness 0.15)
				)
				(justify right bottom)
			)
		)
		(pad "1" smd roundrect
			(at -0.48 0 180)
			(size 0.59 0.64)
			(layers "F.Cu" "F.Paste" "F.Mask")
			(roundrect_rratio 0.25)
			(net 1 "GND")
			(pintype "passive")
		)
		(pad "2" smd roundrect
			(at 0.48 0 180)
			(size 0.59 0.64)
			(layers "F.Cu" "F.Paste" "F.Mask")
			(roundrect_rratio 0.25)
			(net 762 "/Supply/5V_VDRV")
			(pintype "passive")
		)
	)
)
